(kicad_pcb
	(version 20241229)
	(generator "pcbnew")
	(generator_version "9.0")
	(general
		(thickness 1.599998)
		(legacy_teardrops no)
	)
	(paper "A4")
	(title_block
		(title "Artix - Datacenter Secure Control Module (DC-SCM)")
		(date "2024-11-06")
		(rev "1.1.3")
		(comment 9 "footprints 76-81 of 544")
	)
	(layers
		(0 "F.Cu" signal)
		(4 "In1.Cu" signal)
		(6 "In2.Cu" signal)
		(8 "In3.Cu" signal)
		(10 "In4.Cu" signal)
		(12 "In5.Cu" signal)
		(14 "In6.Cu" signal)
		(2 "B.Cu" signal)
		(9 "F.Adhes" user "F.Adhesive")
		(11 "B.Adhes" user "B.Adhesive")
		(13 "F.Paste" user)
		(15 "B.Paste" user)
		(5 "F.SilkS" user "F.Silkscreen")
		(7 "B.SilkS" user "B.Silkscreen")
		(1 "F.Mask" user)
		(3 "B.Mask" user)
		(17 "Dwgs.User" user "User.Drawings")
		(19 "Cmts.User" user "User.Comments")
		(21 "Eco1.User" user "User.Eco1")
		(23 "Eco2.User" user "User.Eco2")
		(25 "Edge.Cuts" user)
		(27 "Margin" user)
		(31 "F.CrtYd" user "F.Courtyard")
		(29 "B.CrtYd" user "B.Courtyard")
		(35 "F.Fab" user)
		(33 "B.Fab" user)
	)
	(footprint "antmicro-footprints:TP_SMD_1mm"
		(layer "F.Cu")
		(at 142.575 161.675)
		(property "Reference" "TP13"
			(at 0.525 0.325 0)
			(layer "F.SilkS")
			(effects
				(font
					(size 0.7 0.7)
					(thickness 0.15)
				)
				(justify left bottom)
			)
		)
		(property "Value" "TP_1mm_SMD"
			(at 0 1.4 0)
			(layer "F.Fab")
			(effects
				(font
					(size 0.7 0.7)
					(thickness 0.15)
				)
				(justify left bottom)
			)
		)
		(property "Description" "Test point 1mm SMD"
			(at 0 0 0)
			(layer "F.Fab")
			(hide yes)
			(effects
				(font
					(size 1.27 1.27)
					(thickness 0.15)
				)
			)
		)
		(property "Author" "Antmicro"
			(at 0 0 0)
			(layer "F.Fab")
			(hide yes)
			(effects
				(font
					(size 1 1)
					(thickness 0.15)
				)
			)
		)
		(property "License" "Apache-2.0"
			(at 0 0 0)
			(layer "F.Fab")
			(hide yes)
			(effects
				(font
					(size 1 1)
					(thickness 0.15)
				)
			)
		)
		(property "MPN" ""
			(at 0 0 0)
			(layer "F.Fab")
			(hide yes)
			(effects
				(font
					(size 1 1)
					(thickness 0.15)
				)
			)
		)
		(property "Manufacturer" ""
			(at 0 0 0)
			(layer "F.Fab")
			(hide yes)
			(effects
				(font
					(size 1 1)
					(thickness 0.15)
				)
			)
		)
		(sheetname "/PCIe-connector/")
		(sheetfile "pcie-conn.kicad_sch")
		(attr exclude_from_pos_files exclude_from_bom)
		(fp_circle
			(center 0 0)
			(end 0.6 0)
			(stroke
				(width 0.05)
				(type default)
			)
			(fill no)
			(layer "F.CrtYd")
		)
		(pad "1" smd circle
			(at 0 0)
			(size 1 1)
			(layers "F.Cu" "F.Mask")
			(net 269 "Net-(J2-~{CLKREQ})")
			(pinfunction "1")
			(pintype "passive")
		)
	)
	(footprint "antmicro-footprints:TP_SMD_1mm"
		(layer "F.Cu")
		(at 142.575 160.2258)
		(property "Reference" "TP14"
			(at 0.525 0.325 0)
			(layer "F.SilkS")
			(effects
				(font
					(size 0.7 0.7)
					(thickness 0.15)
				)
				(justify left bottom)
			)
		)
		(property "Value" "TP_1mm_SMD"
			(at 0 1.4 0)
			(layer "F.Fab")
			(effects
				(font
					(size 0.7 0.7)
					(thickness 0.15)
				)
				(justify left bottom)
			)
		)
		(property "Description" "Test point 1mm SMD"
			(at 0 0 0)
			(layer "F.Fab")
			(hide yes)
			(effects
				(font
					(size 1.27 1.27)
					(thickness 0.15)
				)
			)
		)
		(property "Author" "Antmicro"
			(at 0 0 0)
			(layer "F.Fab")
			(hide yes)
			(effects
				(font
					(size 1 1)
					(thickness 0.15)
				)
			)
		)
		(property "License" "Apache-2.0"
			(at 0 0 0)
			(layer "F.Fab")
			(hide yes)
			(effects
				(font
					(size 1 1)
					(thickness 0.15)
				)
			)
		)
		(property "MPN" ""
			(at 0 0 0)
			(layer "F.Fab")
			(hide yes)
			(effects
				(font
					(size 1 1)
					(thickness 0.15)
				)
			)
		)
		(property "Manufacturer" ""
			(at 0 0 0)
			(layer "F.Fab")
			(hide yes)
			(effects
				(font
					(size 1 1)
					(thickness 0.15)
				)
			)
		)
		(sheetname "/PCIe-connector/")
		(sheetfile "pcie-conn.kicad_sch")
		(attr exclude_from_pos_files exclude_from_bom)
		(fp_circle
			(center 0 0)
			(end 0.6 0)
			(stroke
				(width 0.05)
				(type default)
			)
			(fill no)
			(layer "F.CrtYd")
		)
		(pad "1" smd circle
			(at 0 0)
			(size 1 1)
			(layers "F.Cu" "F.Mask")
			(net 118 "PRSNT1_N")
			(pinfunction "1")
			(pintype "passive")
		)
	)
	(footprint "antmicro-footprints:R_0402_1005Metric"
		(layer "F.Cu")
		(at 71.415 167.865 -90)
		(descr "Resistor SMD 0402")
		(tags "resistor SMD 0402")
		(property "Reference" "R114"
			(at 0.835 -0.385 90)
			(layer "F.SilkS")
			(effects
				(font
					(size 0.7 0.7)
					(thickness 0.15)
				)
				(justify right bottom)
			)
		)
		(property "Value" "R_0R_0402"
			(at 0 1.4 90)
			(layer "F.Fab")
			(effects
				(font
					(size 0.7 0.7)
					(thickness 0.15)
				)
				(justify right bottom)
			)
		)
		(property "Datasheet" "https://industrial.panasonic.com/cdbs/www-data/pdf/RDA0000/AOA0000C301.pdf"
			(at 0 0 270)
			(layer "F.Fab")
			(hide yes)
			(effects
				(font
					(size 1.27 1.27)
					(thickness 0.15)
				)
			)
		)
		(property "Description" "SMD Chip Resistor, Jumper, 0 ohm, 100 mW, 0402 [1005 Metric], Thick Film, General Purpose"
			(at 0 0 270)
			(layer "F.Fab")
			(hide yes)
			(effects
				(font
					(size 1.27 1.27)
					(thickness 0.15)
				)
			)
		)
		(property "Author" "Antmicro"
			(at -96.45 239.28 0)
			(layer "F.Fab")
			(hide yes)
			(effects
				(font
					(size 1 1)
					(thickness 0.15)
				)
			)
		)
		(property "Current" "1A"
			(at -96.45 239.28 0)
			(layer "F.Fab")
			(hide yes)
			(effects
				(font
					(size 1 1)
					(thickness 0.15)
				)
			)
		)
		(property "License" "Apache-2.0"
			(at -96.45 239.28 0)
			(layer "F.Fab")
			(hide yes)
			(effects
				(font
					(size 1 1)
					(thickness 0.15)
				)
			)
		)
		(property "MPN" "ERJ2GE0R00X"
			(at -96.45 239.28 0)
			(layer "F.Fab")
			(hide yes)
			(effects
				(font
					(size 1 1)
					(thickness 0.15)
				)
			)
		)
		(property "Manufacturer" "Panasonic"
			(at -96.45 239.28 0)
			(layer "F.Fab")
			(hide yes)
			(effects
				(font
					(size 1 1)
					(thickness 0.15)
				)
			)
		)
		(property "Tolerance" "~"
			(at -96.45 239.28 0)
			(layer "F.Fab")
			(hide yes)
			(effects
				(font
					(size 1 1)
					(thickness 0.15)
				)
			)
		)
		(property "Val" "0R"
			(at -96.45 239.28 0)
			(layer "F.Fab")
			(hide yes)
			(effects
				(font
					(size 1 1)
					(thickness 0.15)
				)
			)
		)
		(sheetname "/Edge connector/")
		(sheetfile "edge-connector.kicad_sch")
		(attr smd)
		(fp_rect
			(start -0.925 -0.47)
			(end 0.925 0.47)
			(stroke
				(width 0.05)
				(type default)
			)
			(fill no)
			(layer "F.CrtYd")
		)
		(fp_rect
			(start -0.5 -0.25)
			(end 0.5 0.25)
			(stroke
				(width 0.15)
				(type solid)
			)
			(fill no)
			(layer "F.Fab")
		)
		(pad "1" smd roundrect
			(at -0.48 0 270)
			(size 0.59 0.64)
			(layers "F.Cu" "F.Mask" "F.Paste")
			(roundrect_rratio 0.25)
			(net 521 "PRSNT0_N_R")
			(pintype "passive")
		)
		(pad "2" smd roundrect
			(at 0.48 0 270)
			(size 0.59 0.64)
			(layers "F.Cu" "F.Mask" "F.Paste")
			(roundrect_rratio 0.25)
			(net 243 "/Edge connector/PRSNT0_N")
			(pintype "passive")
		)
	)
	(footprint "antmicro-footprints:LED_0603_1608Metric_G"
		(layer "F.Cu")
		(at 67.466 84.215 180)
		(descr "LED SMD 0603 Green")
		(tags "LED SMD 0603 Green")
		(property "Reference" "D10"
			(at -3.434 -0.385 0)
			(layer "F.SilkS")
			(effects
				(font
					(size 0.7 0.7)
					(thickness 0.15)
				)
				(justify right bottom)
			)
		)
		(property "Value" "LED_G_0603_LG_L29K-G2J1-24-Z"
			(at 0 1.6 0)
			(layer "F.Fab")
			(effects
				(font
					(size 0.7 0.7)
					(thickness 0.15)
				)
				(justify right bottom)
			)
		)
		(property "Datasheet" "https://look.ams-osram.com/m/19ee86b3ae0ee95b/original/LG-L29K.pdf"
			(at 0 0 180)
			(layer "F.Fab")
			(hide yes)
			(effects
				(font
					(size 1.27 1.27)
					(thickness 0.15)
				)
			)
		)
		(property "Description" "LED, Green, SMD, 0603, 20 mA, 1.7 V, 570 nm"
			(at 0 0 180)
			(layer "F.Fab")
			(hide yes)
			(effects
				(font
					(size 1.27 1.27)
					(thickness 0.15)
				)
			)
		)
		(property "Author" "Antmicro"
			(at 134.932 168.43 0)
			(layer "F.Fab")
			(hide yes)
			(effects
				(font
					(size 1 1)
					(thickness 0.15)
				)
			)
		)
		(property "Color" "Green"
			(at 134.932 168.43 0)
			(layer "F.Fab")
			(hide yes)
			(effects
				(font
					(size 1 1)
					(thickness 0.15)
				)
			)
		)
		(property "License" "Apache-2.0"
			(at 134.932 168.43 0)
			(layer "F.Fab")
			(hide yes)
			(effects
				(font
					(size 1 1)
					(thickness 0.15)
				)
			)
		)
		(property "MPN" "LG L29K-G2J1-24-Z"
			(at 134.932 168.43 0)
			(layer "F.Fab")
			(hide yes)
			(effects
				(font
					(size 1 1)
					(thickness 0.15)
				)
			)
		)
		(property "Manufacturer" "OSRAM"
			(at 134.932 168.43 0)
			(layer "F.Fab")
			(hide yes)
			(effects
				(font
					(size 1 1)
					(thickness 0.15)
				)
			)
		)
		(sheetname "/FPGA banks 34-35 & CFG/")
		(sheetfile "fpga-banks-34-25-cfg.kicad_sch")
		(attr smd)
		(fp_line
			(start 0.22 0.35)
			(end -0.22 0.35)
			(stroke
				(width 0.15)
				(type solid)
			)
			(layer "F.SilkS")
		)
		(fp_line
			(start 0.22 -0.35)
			(end -0.22 -0.35)
			(stroke
				(width 0.15)
				(type solid)
			)
			(layer "F.SilkS")
		)
		(fp_line
			(start 0.105328 0.201008)
			(end 0.105328 -0.198992)
			(stroke
				(width 0.1)
				(type solid)
			)
			(layer "F.SilkS")
		)
		(fp_line
			(start 0.105328 0.201008)
			(end -0.094672 0.001008)
			(stroke
				(width 0.1)
				(type solid)
			)
			(layer "F.SilkS")
		)
		(fp_line
			(start 0.105328 0.001008)
			(end 0.24 0.001)
			(stroke
				(width 0.1)
				(type solid)
			)
			(layer "F.SilkS")
		)
		(fp_line
			(start -0.094672 0.201008)
			(end -0.094672 -0.198992)
			(stroke
				(width 0.1)
				(type solid)
			)
			(layer "F.SilkS")
		)
		(fp_line
			(start -0.094672 0.001008)
			(end 0.105328 -0.198992)
			(stroke
				(width 0.1)
				(type solid)
			)
			(layer "F.SilkS")
		)
		(fp_line
			(start -0.094672 0.001008)
			(end -0.24 0.001008)
			(stroke
				(width 0.1)
				(type solid)
			)
			(layer "F.SilkS")
		)
		(fp_line
			(start -1.18 -0.319)
			(end -1.18 0.321)
			(stroke
				(width 0.15)
				(type solid)
			)
			(layer "F.SilkS")
		)
		(fp_rect
			(start 1.25 0.65)
			(end -1.25 -0.65)
			(stroke
				(width 0.05)
				(type solid)
			)
			(fill no)
			(layer "F.CrtYd")
		)
		(fp_line
			(start 0.599 0)
			(end 0.201 0)
			(stroke
				(width 0.15)
				(type solid)
			)
			(layer "F.Fab")
		)
		(fp_line
			(start 0.201 0.2)
			(end 0.201 0)
			(stroke
				(width 0.15)
				(type solid)
			)
			(layer "F.Fab")
		)
		(fp_line
			(start 0.201 0)
			(end 0.201 -0.202)
			(stroke
				(width 0.15)
				(type solid)
			)
			(layer "F.Fab")
		)
		(fp_line
			(start 0.201 -0.202)
			(end -0.101 0)
			(stroke
				(width 0.15)
				(type solid)
			)
			(layer "F.Fab")
		)
		(fp_line
			(start -0.101 0)
			(end 0.201 0.2)
			(stroke
				(width 0.15)
				(type solid)
			)
			(layer "F.Fab")
		)
		(fp_line
			(start -0.199 0.2)
			(end -0.199 0.1)
			(stroke
				(width 0.15)
				(type solid)
			)
			(layer "F.Fab")
		)
		(fp_line
			(start -0.199 0)
			(end -0.597 0)
			(stroke
				(width 0.15)
				(type solid)
			)
			(layer "F.Fab")
		)
		(fp_line
			(start -0.199 -0.202)
			(end -0.199 0.1)
			(stroke
				(width 0.15)
				(type solid)
			)
			(layer "F.Fab")
		)
		(fp_rect
			(start 0.848 0.4)
			(end -0.85 -0.402)
			(stroke
				(width 0.15)
				(type solid)
			)
			(fill no)
			(layer "F.Fab")
		)
		(pad "1" smd roundrect
			(at -0.7 0)
			(size 0.8 1)
			(layers "F.Cu" "F.Mask" "F.Paste")
			(roundrect_rratio 0.2)
			(net 281 "Net-(D10-C)")
			(pinfunction "C")
			(pintype "passive")
		)
		(pad "2" smd roundrect
			(at 0.7 0)
			(size 0.8 1)
			(layers "F.Cu" "F.Mask" "F.Paste")
			(roundrect_rratio 0.2)
			(net 283 "Net-(D10-A)")
			(pinfunction "A")
			(pintype "passive")
		)
	)
	(footprint "antmicro-footprints:C_0402_1005Metric"
		(layer "F.Cu")
		(at 103.374 154.675 90)
		(descr "Capacitor SMD 0402")
		(tags "capacitor SMD 0402")
		(property "Reference" "C52"
			(at -3.425 -8.474 90)
			(layer "F.SilkS")
			(effects
				(font
					(size 0.7 0.7)
					(thickness 0.15)
				)
				(justify left bottom)
			)
		)
		(property "Value" "C_470n_0402"
			(at 0 1.4 90)
			(layer "F.Fab")
			(effects
				(font
					(size 0.7 0.7)
					(thickness 0.15)
				)
				(justify left bottom)
			)
		)
		(property "Datasheet" "https://product.tdk.com/en/search/capacitor/ceramic/mlcc/info?part_no=C1005X5R1E474M050BB"
			(at 0 0 90)
			(layer "F.Fab")
			(hide yes)
			(effects
				(font
					(size 1.27 1.27)
					(thickness 0.15)
				)
			)
		)
		(property "Description" "SMD Multilayer Ceramic Capacitor, 0.47 µF, 25 V, 0402 [1005 Metric], ± 20%, X5R, C"
			(at 0 0 90)
			(layer "F.Fab")
			(hide yes)
			(effects
				(font
					(size 1.27 1.27)
					(thickness 0.15)
				)
			)
		)
		(property "Author" "Antmicro"
			(at 258.049 51.301 0)
			(layer "F.Fab")
			(hide yes)
			(effects
				(font
					(size 1 1)
					(thickness 0.15)
				)
			)
		)
		(property "Dielectric" ""
			(at 258.049 51.301 0)
			(layer "F.Fab")
			(hide yes)
			(effects
				(font
					(size 1 1)
					(thickness 0.15)
				)
			)
		)
		(property "License" "Apache-2.0"
			(at 258.049 51.301 0)
			(layer "F.Fab")
			(hide yes)
			(effects
				(font
					(size 1 1)
					(thickness 0.15)
				)
			)
		)
		(property "MPN" "C1005X5R1E474M050BB"
			(at 258.049 51.301 0)
			(layer "F.Fab")
			(hide yes)
			(effects
				(font
					(size 1 1)
					(thickness 0.15)
				)
			)
		)
		(property "Manufacturer" "TDK"
			(at 258.049 51.301 0)
			(layer "F.Fab")
			(hide yes)
			(effects
				(font
					(size 1 1)
					(thickness 0.15)
				)
			)
		)
		(property "Val" "470n"
			(at 258.049 51.301 0)
			(layer "F.Fab")
			(hide yes)
			(effects
				(font
					(size 1 1)
					(thickness 0.15)
				)
			)
		)
		(property "Voltage" ""
			(at 258.049 51.301 0)
			(layer "F.Fab")
			(hide yes)
			(effects
				(font
					(size 1 1)
					(thickness 0.15)
				)
			)
		)
		(sheetname "/DDR3/")
		(sheetfile "ddr3.kicad_sch")
		(attr smd)
		(fp_rect
			(start -0.925 -0.47)
			(end 0.925 0.47)
			(stroke
				(width 0.05)
				(type default)
			)
			(fill no)
			(layer "F.CrtYd")
		)
		(fp_line
			(start 0.504 -0.25)
			(end 0.504 0.248)
			(stroke
				(width 0.15)
				(type solid)
			)
			(layer "F.Fab")
		)
		(fp_line
			(start -0.494 -0.25)
			(end 0.504 -0.25)
			(stroke
				(width 0.15)
				(type solid)
			)
			(layer "F.Fab")
		)
		(fp_line
			(start 0.504 0.248)
			(end -0.494 0.248)
			(stroke
				(width 0.15)
				(type solid)
			)
			(layer "F.Fab")
		)
		(fp_line
			(start -0.494 0.248)
			(end -0.494 -0.25)
			(stroke
				(width 0.15)
				(type solid)
			)
			(layer "F.Fab")
		)
		(pad "1" smd roundrect
			(at -0.48 0 90)
			(size 0.59 0.64)
			(layers "F.Cu" "F.Mask" "F.Paste")
			(roundrect_rratio 0.25)
			(net 1 "GND")
			(pintype "passive")
		)
		(pad "2" smd roundrect
			(at 0.48 0 90)
			(size 0.59 0.64)
			(layers "F.Cu" "F.Mask" "F.Paste")
			(roundrect_rratio 0.25)
			(net 3 "VCC1V35")
			(pintype "passive")
		)
	)
	(footprint "antmicro-footprints:C_0402_1005Metric"
		(layer "F.Cu")
		(at 101.774 140.075 -90)
		(descr "Capacitor SMD 0402")
		(tags "capacitor SMD 0402")
		(property "Reference" "C56"
			(at -2.975 -0.326 90)
			(layer "F.SilkS")
			(effects
				(font
					(size 0.7 0.7)
					(thickness 0.15)
				)
				(justify right bottom)
			)
		)
		(property "Value" "C_470n_0402"
			(at 0 1.4 90)
			(layer "F.Fab")
			(effects
				(font
					(size 0.7 0.7)
					(thickness 0.15)
				)
				(justify right bottom)
			)
		)
		(property "Datasheet" "https://product.tdk.com/en/search/capacitor/ceramic/mlcc/info?part_no=C1005X5R1E474M050BB"
			(at 0 0 270)
			(layer "F.Fab")
			(hide yes)
			(effects
				(font
					(size 1.27 1.27)
					(thickness 0.15)
				)
			)
		)
		(property "Description" "SMD Multilayer Ceramic Capacitor, 0.47 µF, 25 V, 0402 [1005 Metric], ± 20%, X5R, C"
			(at 0 0 270)
			(layer "F.Fab")
			(hide yes)
			(effects
				(font
					(size 1.27 1.27)
					(thickness 0.15)
				)
			)
		)
		(property "Author" "Antmicro"
			(at -38.301 241.849 0)
			(layer "F.Fab")
			(hide yes)
			(effects
				(font
					(size 1 1)
					(thickness 0.15)
				)
			)
		)
		(property "Dielectric" ""
			(at -38.301 241.849 0)
			(layer "F.Fab")
			(hide yes)
			(effects
				(font
					(size 1 1)
					(thickness 0.15)
				)
			)
		)
		(property "License" "Apache-2.0"
			(at -38.301 241.849 0)
			(layer "F.Fab")
			(hide yes)
			(effects
				(font
					(size 1 1)
					(thickness 0.15)
				)
			)
		)
		(property "MPN" "C1005X5R1E474M050BB"
			(at -38.301 241.849 0)
			(layer "F.Fab")
			(hide yes)
			(effects
				(font
					(size 1 1)
					(thickness 0.15)
				)
			)
		)
		(property "Manufacturer" "TDK"
			(at -38.301 241.849 0)
			(layer "F.Fab")
			(hide yes)
			(effects
				(font
					(size 1 1)
					(thickness 0.15)
				)
			)
		)
		(property "Val" "470n"
			(at -38.301 241.849 0)
			(layer "F.Fab")
			(hide yes)
			(effects
				(font
					(size 1 1)
					(thickness 0.15)
				)
			)
		)
		(property "Voltage" ""
			(at -38.301 241.849 0)
			(layer "F.Fab")
			(hide yes)
			(effects
				(font
					(size 1 1)
					(thickness 0.15)
				)
			)
		)
		(sheetname "/DDR3/")
		(sheetfile "ddr3.kicad_sch")
		(attr smd)
		(fp_rect
			(start -0.925 -0.47)
			(end 0.925 0.47)
			(stroke
				(width 0.05)
				(type default)
			)
			(fill no)
			(layer "F.CrtYd")
		)
		(fp_line
			(start -0.494 0.248)
			(end -0.494 -0.25)
			(stroke
				(width 0.15)
				(type solid)
			)
			(layer "F.Fab")
		)
		(fp_line
			(start 0.504 0.248)
			(end -0.494 0.248)
			(stroke
				(width 0.15)
				(type solid)
			)
			(layer "F.Fab")
		)
		(fp_line
			(start -0.494 -0.25)
			(end 0.504 -0.25)
			(stroke
				(width 0.15)
				(type solid)
			)
			(layer "F.Fab")
		)
		(fp_line
			(start 0.504 -0.25)
			(end 0.504 0.248)
			(stroke
				(width 0.15)
				(type solid)
			)
			(layer "F.Fab")
		)
		(pad "1" smd roundrect
			(at -0.48 0 270)
			(size 0.59 0.64)
			(layers "F.Cu" "F.Mask" "F.Paste")
			(roundrect_rratio 0.25)
			(net 1 "GND")
			(pintype "passive")
		)
		(pad "2" smd roundrect
			(at 0.48 0 270)
			(size 0.59 0.64)
			(layers "F.Cu" "F.Mask" "F.Paste")
			(roundrect_rratio 0.25)
			(net 3 "VCC1V35")
			(pintype "passive")
		)
	)
)
